# T6G (Grand Teton) — schematic netlist excerpt (pin names and nets, part order shuffled) for the footprints in the layout excerpt that follows; sources: Cadence DE-HDL packaged netlist, KiCad conversion of 04192023_DAF0TMB3IC0_F0TG_MB_C_brd_V02_OCP.brd

C331  Q_CAP  4.7UF 6.3V 20% X6S  pkg 0402  page 334 : A = P0V9_CPU1_RT1_2A ; B = GND
R4575  Q_RES  0 5% EMPTY  pkg 0402LF  page 125 : A = GPU_3V3IO_RSVD0_FFU ; B = GPU_3V3IO_RSVD0_FFU_ISO

(kicad_pcb
	(version 20260206)
	(generator "pcbnew")
	(generator_version "10.0")
	(general
		(thickness 1.6)
		(legacy_teardrops no)
	)
	(paper "A4")
	(title_block
		(title "04192023_DAF0TMB3IC0_F0TG_MB_C_brd_V02_OCP.brd")
		(comment 1 "Grand Teton / footprints 7164-7165 of 8354")
	)
	(layers
		(0 "F.Cu" signal "TOP")
		(4 "In1.Cu" signal "GND")
		(6 "In2.Cu" signal "IN1")
		(8 "In3.Cu" signal "GND1")
		(10 "In4.Cu" signal "IN2")
		(12 "In5.Cu" signal "GND2")
		(14 "In6.Cu" signal "IN3")
		(16 "In7.Cu" signal "GND3")
		(18 "In8.Cu" signal "VCC")
		(20 "In9.Cu" signal "VCC1")
		(22 "In10.Cu" signal "GND4")
		(24 "In11.Cu" signal "IN4")
		(26 "In12.Cu" signal "GND5")
		(28 "In13.Cu" signal "IN5")
		(30 "In14.Cu" signal "GND6")
		(32 "In15.Cu" signal "IN6")
		(34 "In16.Cu" signal "GND7")
		(2 "B.Cu" signal "BOTTOM")
		(9 "F.Adhes" user "F.Adhesive")
		(11 "B.Adhes" user "B.Adhesive")
		(13 "F.Paste" user "Package Geometry/Pastemask Top")
		(15 "B.Paste" user "Package Geometry/Pastemask Bottom")
		(5 "F.SilkS" user "Ref Des/Silkscreen Top")
		(7 "B.SilkS" user "Ref Des/Silkscreen Bottom")
		(1 "F.Mask" user "Board Geometry/Soldermask Top")
		(3 "B.Mask" user "Board Geometry/Soldermask Bottom")
		(17 "Dwgs.User" user "User.Drawings")
		(19 "Cmts.User" user "User.Comments")
		(21 "Eco1.User" user "User.Eco1")
		(23 "Eco2.User" user "User.Eco2")
		(25 "Edge.Cuts" user "Board Geometry/Outline")
		(27 "Margin" user)
		(31 "F.CrtYd" user "Package Geometry/Place Bound Top")
		(29 "B.CrtYd" user "Package Geometry/Place Bound Bottom")
		(35 "F.Fab" user "Ref Des/Assembly Top")
		(33 "B.Fab" user "Ref Des/Assembly Bottom")
	)
	(footprint ""
		(layer "B.Cu")
		(at 166.577518 -415.930588 180)
		(property "Reference" "R4575"
			(at 0 0 0)
			(layer "B.SilkS")
			(hide yes)
			(effects
				(font
					(size 1.27 1.27)
				)
				(justify mirror)
			)
		)
		(property "Value" ""
			(at 0 0 0)
			(layer "B.Fab")
			(effects
				(font
					(size 1.27 1.27)
				)
				(justify mirror)
			)
		)
		(duplicate_pad_numbers_are_jumpers no)
		(fp_line
			(start 0.7874 0.4064)
			(end 0.7874 -0.4064)
			(stroke
				(width 0.1524)
				(type default)
			)
			(layer "B.SilkS")
		)
		(fp_line
			(start 0.7874 -0.4064)
			(end -0.7874 -0.4064)
			(stroke
				(width 0.1524)
				(type default)
			)
			(layer "B.SilkS")
		)
		(fp_line
			(start -0.7874 0.4064)
			(end 0.7874 0.4064)
			(stroke
				(width 0.1524)
				(type default)
			)
			(layer "B.SilkS")
		)
		(fp_line
			(start -0.7874 -0.4064)
			(end -0.7874 0.4064)
			(stroke
				(width 0.1524)
				(type default)
			)
			(layer "B.SilkS")
		)
		(fp_line
			(start 0.67945 0.3048)
			(end 0.67945 -0.305054)
			(stroke
				(width 0.1)
				(type default)
			)
			(layer "B.Fab")
		)
		(fp_line
			(start 0.67945 -0.305054)
			(end 0.12065 -0.305054)
			(stroke
				(width 0.1)
				(type default)
			)
			(layer "B.Fab")
		)
		(fp_line
			(start 0.12065 0.3048)
			(end 0.67945 0.3048)
			(stroke
				(width 0.1)
				(type default)
			)
			(layer "B.Fab")
		)
		(fp_line
			(start 0.12065 0.2794)
			(end 0.12065 0.3048)
			(stroke
				(width 0.1)
				(type default)
			)
			(layer "B.Fab")
		)
		(fp_line
			(start 0.12065 -0.2794)
			(end -0.12065 -0.2794)
			(stroke
				(width 0.1)
				(type default)
			)
			(layer "B.Fab")
		)
		(fp_line
			(start 0.12065 -0.305054)
			(end 0.12065 -0.2794)
			(stroke
				(width 0.1)
				(type default)
			)
			(layer "B.Fab")
		)
		(fp_line
			(start -0.120396 0.3048)
			(end -0.120396 0.2794)
			(stroke
				(width 0.1)
				(type default)
			)
			(layer "B.Fab")
		)
		(fp_line
			(start -0.120396 0.2794)
			(end 0.12065 0.2794)
			(stroke
				(width 0.1)
				(type default)
			)
			(layer "B.Fab")
		)
		(fp_line
			(start -0.12065 -0.2794)
			(end -0.12065 -0.3048)
			(stroke
				(width 0.1)
				(type default)
			)
			(layer "B.Fab")
		)
		(fp_line
			(start -0.12065 -0.3048)
			(end -0.67945 -0.3048)
			(stroke
				(width 0.1)
				(type default)
			)
			(layer "B.Fab")
		)
		(fp_line
			(start -0.67945 0.3048)
			(end -0.120396 0.3048)
			(stroke
				(width 0.1)
				(type default)
			)
			(layer "B.Fab")
		)
		(fp_line
			(start -0.67945 -0.3048)
			(end -0.67945 0.3048)
			(stroke
				(width 0.1)
				(type default)
			)
			(layer "B.Fab")
		)
		(pad "1" smd circle
			(at 0.40005 0)
			(size 0 0)
			(layers "B.Cu" "B.Mask" "B.Paste")
			(net "GPU_3V3IO_RSVD0_FFU")
		)
		(pad "2" smd circle
			(at -0.40005 0)
			(size 0 0)
			(layers "B.Cu" "B.Mask" "B.Paste")
			(net "GPU_3V3IO_RSVD0_FFU_ISO")
		)
	)
	(footprint ""
		(layer "B.Cu")
		(at 96.719136 -390.560052 90)
		(property "Reference" "C331"
			(at 0 0 90)
			(layer "B.SilkS")
			(hide yes)
			(effects
				(font
					(size 1.27 1.27)
				)
				(justify mirror)
			)
		)
		(property "Value" ""
			(at 0 0 90)
			(layer "B.Fab")
			(effects
				(font
					(size 1.27 1.27)
				)
				(justify mirror)
			)
		)
		(duplicate_pad_numbers_are_jumpers no)
		(fp_line
			(start 0.7874 -0.4064)
			(end -0.7874 -0.4064)
			(stroke
				(width 0.1524)
				(type default)
			)
			(layer "B.SilkS")
		)
		(fp_line
			(start -0.7874 -0.4064)
			(end -0.7874 0.4064)
			(stroke
				(width 0.1524)
				(type default)
			)
			(layer "B.SilkS")
		)
		(fp_line
			(start 0.7874 0.4064)
			(end 0.7874 -0.4064)
			(stroke
				(width 0.1524)
				(type default)
			)
			(layer "B.SilkS")
		)
		(fp_line
			(start -0.7874 0.4064)
			(end 0.7874 0.4064)
			(stroke
				(width 0.1524)
				(type default)
			)
			(layer "B.SilkS")
		)
		(fp_line
			(start 0.67945 -0.305054)
			(end 0.12065 -0.305054)
			(stroke
				(width 0.1)
				(type default)
			)
			(layer "B.Fab")
		)
		(fp_line
			(start 0.12065 -0.305054)
			(end 0.12065 -0.2794)
			(stroke
				(width 0.1)
				(type default)
			)
			(layer "B.Fab")
		)
		(fp_line
			(start -0.12065 -0.3048)
			(end -0.67945 -0.3048)
			(stroke
				(width 0.1)
				(type default)
			)
			(layer "B.Fab")
		)
		(fp_line
			(start -0.67945 -0.3048)
			(end -0.67945 0.3048)
			(stroke
				(width 0.1)
				(type default)
			)
			(layer "B.Fab")
		)
		(fp_line
			(start 0.12065 -0.2794)
			(end -0.12065 -0.2794)
			(stroke
				(width 0.1)
				(type default)
			)
			(layer "B.Fab")
		)
		(fp_line
			(start -0.12065 -0.2794)
			(end -0.12065 -0.3048)
			(stroke
				(width 0.1)
				(type default)
			)
			(layer "B.Fab")
		)
		(fp_line
			(start 0.12065 0.2794)
			(end 0.12065 0.3048)
			(stroke
				(width 0.1)
				(type default)
			)
			(layer "B.Fab")
		)
		(fp_line
			(start -0.120396 0.2794)
			(end 0.12065 0.2794)
			(stroke
				(width 0.1)
				(type default)
			)
			(layer "B.Fab")
		)
		(fp_line
			(start 0.67945 0.3048)
			(end 0.67945 -0.305054)
			(stroke
				(width 0.1)
				(type default)
			)
			(layer "B.Fab")
		)
		(fp_line
			(start 0.12065 0.3048)
			(end 0.67945 0.3048)
			(stroke
				(width 0.1)
				(type default)
			)
			(layer "B.Fab")
		)
		(fp_line
			(start -0.120396 0.3048)
			(end -0.120396 0.2794)
			(stroke
				(width 0.1)
				(type default)
			)
			(layer "B.Fab")
		)
		(fp_line
			(start -0.67945 0.3048)
			(end -0.120396 0.3048)
			(stroke
				(width 0.1)
				(type default)
			)
			(layer "B.Fab")
		)
		(pad "1" smd circle
			(at 0.40005 0 270)
			(size 0 0)
			(layers "B.Cu" "B.Mask" "B.Paste")
			(net "P0V9_CPU1_RT1_2A")
		)
		(pad "2" smd circle
			(at -0.40005 0 270)
			(size 0 0)
			(layers "B.Cu" "B.Mask" "B.Paste")
			(net "GND")
		)
	)
)
